(kicad_pcb
	(version 20260206)
	(generator "pcbnew")
	(generator_version "10.0")
	(general
		(thickness 1.6)
		(legacy_teardrops no)
	)
	(paper "A4")
	(title_block
		(title "timecard-production-celestica-r4006 — R4006-B0001-02_R01.brd")
		(comment 1 "Time Appliance Project (Time Card) / footprints 722-726 of 1113")
	)
	(layers
		(0 "F.Cu" signal "TOP")
		(4 "In1.Cu" signal "L02_GND1")
		(6 "In2.Cu" signal "L03_SIG1")
		(8 "In3.Cu" signal "L04_GND2")
		(10 "In4.Cu" signal "L05_VCC1")
		(12 "In5.Cu" signal "L06_VCC2")
		(14 "In6.Cu" signal "L07_GND3")
		(16 "In7.Cu" signal "L08_SIG2")
		(18 "In8.Cu" signal "L09_GND4")
		(2 "B.Cu" signal "BOTTOM")
		(9 "F.Adhes" user "F.Adhesive")
		(11 "B.Adhes" user "B.Adhesive")
		(13 "F.Paste" user "Package Geometry/Pastemask Top")
		(15 "B.Paste" user "Package Geometry/Pastemask Bottom")
		(5 "F.SilkS" user "Ref Des/Silkscreen Top")
		(7 "B.SilkS" user "Ref Des/Silkscreen Bottom")
		(1 "F.Mask" user "Board Geometry/Soldermask Top")
		(3 "B.Mask" user "Board Geometry/Soldermask Bottom")
		(17 "Dwgs.User" user "User.Drawings")
		(19 "Cmts.User" user "User.Comments")
		(21 "Eco1.User" user "User.Eco1")
		(23 "Eco2.User" user "User.Eco2")
		(25 "Edge.Cuts" user "Board Geometry/Outline")
		(27 "Margin" user)
		(31 "F.CrtYd" user "Package Geometry/Place Bound Top")
		(29 "B.CrtYd" user "Package Geometry/Place Bound Bottom")
		(35 "F.Fab" user "Ref Des/Assembly Top")
		(33 "B.Fab" user "Ref Des/Assembly Bottom")
	)
	(footprint ""
		(layer "B.Cu")
		(at 22.606 -86.614 180)
		(property "Reference" "R470"
			(at -1.016 -3.34137 0)
			(unlocked yes)
			(layer "B.SilkS")
			(effects
				(font
					(size 0.7874 0.5842)
					(thickness 0.1524)
				)
				(justify mirror)
			)
		)
		(property "Value" "VAL*"
			(at -0.02032 2.13233 180)
			(unlocked yes)
			(layer "B.Fab")
			(hide yes)
			(effects
				(font
					(size 0.7874 0.5842)
					(thickness 0.1524)
				)
				(justify mirror)
			)
		)
		(property "Tolerance" "TOL*"
			(at -0.044704 3.05435 180)
			(unlocked yes)
			(layer "Cmts.User")
			(hide yes)
			(effects
				(font
					(size 0.7874 0.5842)
					(thickness 0.1524)
				)
				(justify mirror)
			)
		)
		(property "User Part Number" "PARTNUM*"
			(at -0.02032 4.024884 180)
			(unlocked yes)
			(layer "Cmts.User")
			(hide yes)
			(effects
				(font
					(size 0.7874 0.5842)
					(thickness 0.1524)
				)
				(justify mirror)
			)
		)
		(property "Device Type" "RESISTOR-G155-133R0-01,33OHM,1%"
			(at -0.008382 1.210564 180)
			(unlocked yes)
			(layer "B.Fab")
			(hide yes)
			(effects
				(font
					(size 0.7874 0.5842)
					(thickness 0.1524)
				)
				(justify mirror)
			)
		)
		(duplicate_pad_numbers_are_jumpers no)
		(fp_line
			(start 1.143 0.5588)
			(end -1.143 0.5588)
			(stroke
				(width 0.1)
				(type default)
			)
			(layer "B.SilkS")
		)
		(fp_line
			(start 1.143 -0.5588)
			(end 1.143 0.5588)
			(stroke
				(width 0.1)
				(type default)
			)
			(layer "B.SilkS")
		)
		(fp_line
			(start -1.143 0.5588)
			(end -1.143 -0.5588)
			(stroke
				(width 0.1)
				(type default)
			)
			(layer "B.SilkS")
		)
		(fp_line
			(start -1.143 -0.5588)
			(end 1.143 -0.5588)
			(stroke
				(width 0.1)
				(type default)
			)
			(layer "B.SilkS")
		)
		(fp_poly
			(pts
				(xy 1.143 0.5588) (xy -1.143 0.5588) (xy -1.143 -0.5588) (xy 1.143 -0.5588)
			)
			(stroke
				(width 0)
				(type default)
			)
			(fill no)
			(layer "B.CrtYd")
		)
		(fp_line
			(start 0.508 0.3048)
			(end -0.508 0.3048)
			(stroke
				(width 0.1)
				(type default)
			)
			(layer "B.Fab")
		)
		(fp_line
			(start 0.508 -0.3048)
			(end 0.508 0.3048)
			(stroke
				(width 0.1)
				(type default)
			)
			(layer "B.Fab")
		)
		(fp_line
			(start -0.508 0.3048)
			(end -0.508 -0.3048)
			(stroke
				(width 0.1)
				(type default)
			)
			(layer "B.Fab")
		)
		(fp_line
			(start -0.508 -0.3048)
			(end 0.508 -0.3048)
			(stroke
				(width 0.1)
				(type default)
			)
			(layer "B.Fab")
		)
		(pad "1" smd rect
			(at 0.5334 0)
			(size 0.7112 0.6096)
			(layers "B.Cu" "B.Mask" "B.Paste")
			(net "R_FT4232_TMS")
		)
		(pad "2" smd rect
			(at -0.5334 0)
			(size 0.7112 0.6096)
			(layers "B.Cu" "B.Mask" "B.Paste")
			(net "FT4232_TMS_SPICS_N")
		)
		(zone
			(layer "B.Cu")
			(hatch none 0.5)
			(connect_pads
				(clearance 0)
			)
			(min_thickness 0.25)
			(keepout
				(tracks not_allowed)
				(vias allowed)
				(pads allowed)
				(copperpour not_allowed)
				(footprints allowed)
			)
			(placement
				(enabled no)
				(sheetname "")
			)
			(fill
				(thermal_gap 0.5)
				(thermal_bridge_width 0.5)
				(island_removal_mode 0)
			)
			(polygon
				(pts
					(xy 22.5298 -86.9188) (xy 22.5298 -86.3092) (xy 22.6822 -86.3092) (xy 22.6822 -86.9188)
				)
			)
		)
		(zone
			(layer "B.Cu")
			(hatch none 0.5)
			(connect_pads
				(clearance 0)
			)
			(min_thickness 0.25)
			(keepout
				(tracks allowed)
				(vias not_allowed)
				(pads allowed)
				(copperpour not_allowed)
				(footprints allowed)
			)
			(placement
				(enabled no)
				(sheetname "")
			)
			(fill
				(thermal_gap 0.5)
				(thermal_bridge_width 0.5)
				(island_removal_mode 0)
			)
			(polygon
				(pts
					(xy 22.5298 -86.9188) (xy 22.5298 -86.3092) (xy 22.6822 -86.3092) (xy 22.6822 -86.9188)
				)
			)
		)
	)
	(footprint ""
		(layer "B.Cu")
		(at 22.606 -87.757 180)
		(property "Reference" "R466"
			(at -1.016 -3.46837 0)
			(unlocked yes)
			(layer "B.SilkS")
			(effects
				(font
					(size 0.7874 0.5842)
					(thickness 0.1524)
				)
				(justify mirror)
			)
		)
		(property "Value" "VAL*"
			(at -0.02032 2.13233 180)
			(unlocked yes)
			(layer "B.Fab")
			(hide yes)
			(effects
				(font
					(size 0.7874 0.5842)
					(thickness 0.1524)
				)
				(justify mirror)
			)
		)
		(property "Tolerance" "TOL*"
			(at -0.044704 3.05435 180)
			(unlocked yes)
			(layer "Cmts.User")
			(hide yes)
			(effects
				(font
					(size 0.7874 0.5842)
					(thickness 0.1524)
				)
				(justify mirror)
			)
		)
		(property "User Part Number" "PARTNUM*"
			(at -0.02032 4.024884 180)
			(unlocked yes)
			(layer "Cmts.User")
			(hide yes)
			(effects
				(font
					(size 0.7874 0.5842)
					(thickness 0.1524)
				)
				(justify mirror)
			)
		)
		(property "Device Type" "RESISTOR-G155-11003-01,100KOHMA"
			(at -0.008382 1.210564 180)
			(unlocked yes)
			(layer "B.Fab")
			(hide yes)
			(effects
				(font
					(size 0.7874 0.5842)
					(thickness 0.1524)
				)
				(justify mirror)
			)
		)
		(duplicate_pad_numbers_are_jumpers no)
		(fp_line
			(start 1.143 0.5588)
			(end -1.143 0.5588)
			(stroke
				(width 0.1)
				(type default)
			)
			(layer "B.SilkS")
		)
		(fp_line
			(start 1.143 -0.5588)
			(end 1.143 0.5588)
			(stroke
				(width 0.1)
				(type default)
			)
			(layer "B.SilkS")
		)
		(fp_line
			(start -1.143 0.5588)
			(end -1.143 -0.5588)
			(stroke
				(width 0.1)
				(type default)
			)
			(layer "B.SilkS")
		)
		(fp_line
			(start -1.143 -0.5588)
			(end 1.143 -0.5588)
			(stroke
				(width 0.1)
				(type default)
			)
			(layer "B.SilkS")
		)
		(fp_poly
			(pts
				(xy 1.143 0.5588) (xy -1.143 0.5588) (xy -1.143 -0.5588) (xy 1.143 -0.5588)
			)
			(stroke
				(width 0)
				(type default)
			)
			(fill no)
			(layer "B.CrtYd")
		)
		(fp_line
			(start 0.508 0.3048)
			(end -0.508 0.3048)
			(stroke
				(width 0.1)
				(type default)
			)
			(layer "B.Fab")
		)
		(fp_line
			(start 0.508 -0.3048)
			(end 0.508 0.3048)
			(stroke
				(width 0.1)
				(type default)
			)
			(layer "B.Fab")
		)
		(fp_line
			(start -0.508 0.3048)
			(end -0.508 -0.3048)
			(stroke
				(width 0.1)
				(type default)
			)
			(layer "B.Fab")
		)
		(fp_line
			(start -0.508 -0.3048)
			(end 0.508 -0.3048)
			(stroke
				(width 0.1)
				(type default)
			)
			(layer "B.Fab")
		)
		(pad "1" smd rect
			(at 0.5334 0)
			(size 0.7112 0.6096)
			(layers "B.Cu" "B.Mask" "B.Paste")
			(net "R_FT4232_TDO")
		)
		(pad "2" smd rect
			(at -0.5334 0)
			(size 0.7112 0.6096)
			(layers "B.Cu" "B.Mask" "B.Paste")
			(net "XP3R3V_FT4232")
		)
		(zone
			(layer "B.Cu")
			(hatch none 0.5)
			(connect_pads
				(clearance 0)
			)
			(min_thickness 0.25)
			(keepout
				(tracks allowed)
				(vias not_allowed)
				(pads allowed)
				(copperpour not_allowed)
				(footprints allowed)
			)
			(placement
				(enabled no)
				(sheetname "")
			)
			(fill
				(thermal_gap 0.5)
				(thermal_bridge_width 0.5)
				(island_removal_mode 0)
			)
			(polygon
				(pts
					(xy 22.5298 -88.0618) (xy 22.5298 -87.4522) (xy 22.6822 -87.4522) (xy 22.6822 -88.0618)
				)
			)
		)
		(zone
			(layer "B.Cu")
			(hatch none 0.5)
			(connect_pads
				(clearance 0)
			)
			(min_thickness 0.25)
			(keepout
				(tracks not_allowed)
				(vias allowed)
				(pads allowed)
				(copperpour not_allowed)
				(footprints allowed)
			)
			(placement
				(enabled no)
				(sheetname "")
			)
			(fill
				(thermal_gap 0.5)
				(thermal_bridge_width 0.5)
				(island_removal_mode 0)
			)
			(polygon
				(pts
					(xy 22.5298 -88.0618) (xy 22.5298 -87.4522) (xy 22.6822 -87.4522) (xy 22.6822 -88.0618)
				)
			)
		)
	)
	(footprint ""
		(layer "B.Cu")
		(at 120.8278 -90.1954)
		(property "Reference" "R115"
			(at -0.4318 -1.20523 0)
			(unlocked yes)
			(layer "B.SilkS")
			(effects
				(font
					(size 0.7874 0.5842)
					(thickness 0.1524)
				)
				(justify mirror)
			)
		)
		(property "Value" "VAL*"
			(at -0.02032 2.13233 0)
			(unlocked yes)
			(layer "B.Fab")
			(hide yes)
			(effects
				(font
					(size 0.7874 0.5842)
					(thickness 0.1524)
				)
				(justify mirror)
			)
		)
		(property "Device Type" "RESISTOR-G155-14701-01,4.7KOHMA"
			(at -0.008382 1.210564 0)
			(unlocked yes)
			(layer "B.Fab")
			(hide yes)
			(effects
				(font
					(size 0.7874 0.5842)
					(thickness 0.1524)
				)
				(justify mirror)
			)
		)
		(property "User Part Number" "PARTNUM*"
			(at -0.02032 4.024884 0)
			(unlocked yes)
			(layer "Cmts.User")
			(hide yes)
			(effects
				(font
					(size 0.7874 0.5842)
					(thickness 0.1524)
				)
				(justify mirror)
			)
		)
		(property "Tolerance" "TOL*"
			(at -0.044704 3.05435 0)
			(unlocked yes)
			(layer "Cmts.User")
			(hide yes)
			(effects
				(font
					(size 0.7874 0.5842)
					(thickness 0.1524)
				)
				(justify mirror)
			)
		)
		(duplicate_pad_numbers_are_jumpers no)
		(fp_line
			(start -1.143 -0.5588)
			(end 1.143 -0.5588)
			(stroke
				(width 0.1)
				(type default)
			)
			(layer "B.SilkS")
		)
		(fp_line
			(start -1.143 0.5588)
			(end -1.143 -0.5588)
			(stroke
				(width 0.1)
				(type default)
			)
			(layer "B.SilkS")
		)
		(fp_line
			(start 1.143 -0.5588)
			(end 1.143 0.5588)
			(stroke
				(width 0.1)
				(type default)
			)
			(layer "B.SilkS")
		)
		(fp_line
			(start 1.143 0.5588)
			(end -1.143 0.5588)
			(stroke
				(width 0.1)
				(type default)
			)
			(layer "B.SilkS")
		)
		(fp_rect
			(start 1.143 -0.5588)
			(end -1.143 0.5588)
			(stroke
				(width 0)
				(type default)
			)
			(fill no)
			(layer "B.CrtYd")
		)
		(fp_line
			(start -0.508 -0.3048)
			(end 0.508 -0.3048)
			(stroke
				(width 0.1)
				(type default)
			)
			(layer "B.Fab")
		)
		(fp_line
			(start -0.508 0.3048)
			(end -0.508 -0.3048)
			(stroke
				(width 0.1)
				(type default)
			)
			(layer "B.Fab")
		)
		(fp_line
			(start 0.508 -0.3048)
			(end 0.508 0.3048)
			(stroke
				(width 0.1)
				(type default)
			)
			(layer "B.Fab")
		)
		(fp_line
			(start 0.508 0.3048)
			(end -0.508 0.3048)
			(stroke
				(width 0.1)
				(type default)
			)
			(layer "B.Fab")
		)
		(pad "1" smd rect
			(at 0.5334 0 180)
			(size 0.7112 0.6096)
			(layers "B.Cu" "B.Mask" "B.Paste")
			(net "XP3R3V_GPS")
		)
		(pad "2" smd rect
			(at -0.5334 0 180)
			(size 0.7112 0.6096)
			(layers "B.Cu" "B.Mask" "B.Paste")
			(net "GPS_RST_N")
		)
		(zone
			(layer "B.Cu")
			(hatch none 0.5)
			(connect_pads
				(clearance 0)
			)
			(min_thickness 0.25)
			(keepout
				(tracks allowed)
				(vias not_allowed)
				(pads allowed)
				(copperpour not_allowed)
				(footprints allowed)
			)
			(placement
				(enabled no)
				(sheetname "")
			)
			(fill
				(thermal_gap 0.5)
				(thermal_bridge_width 0.5)
				(island_removal_mode 0)
			)
			(polygon
				(pts
					(xy 120.904 -90.5002) (xy 120.7516 -90.5002) (xy 120.7516 -89.8906) (xy 120.904 -89.8906)
				)
			)
		)
	)
	(footprint ""
		(layer "B.Cu")
		(at 139.954 -59.563 90)
		(property "Reference" "R244"
			(at 3.175 -0.16637 270)
			(unlocked yes)
			(layer "B.SilkS")
			(effects
				(font
					(size 0.7874 0.5842)
					(thickness 0.1524)
				)
				(justify mirror)
			)
		)
		(property "Value" "VAL*"
			(at -0.02032 2.13233 90)
			(unlocked yes)
			(layer "B.Fab")
			(hide yes)
			(effects
				(font
					(size 0.7874 0.5842)
					(thickness 0.1524)
				)
				(justify mirror)
			)
		)
		(property "Device Type" "RESISTOR-G155-100R0-J0,0OHM,-"
			(at -0.008382 1.210564 90)
			(unlocked yes)
			(layer "B.Fab")
			(hide yes)
			(effects
				(font
					(size 0.7874 0.5842)
					(thickness 0.1524)
				)
				(justify mirror)
			)
		)
		(property "User Part Number" "PARTNUM*"
			(at -0.02032 4.024884 90)
			(unlocked yes)
			(layer "Cmts.User")
			(hide yes)
			(effects
				(font
					(size 0.7874 0.5842)
					(thickness 0.1524)
				)
				(justify mirror)
			)
		)
		(property "Tolerance" "TOL*"
			(at -0.044704 3.05435 90)
			(unlocked yes)
			(layer "Cmts.User")
			(hide yes)
			(effects
				(font
					(size 0.7874 0.5842)
					(thickness 0.1524)
				)
				(justify mirror)
			)
		)
		(duplicate_pad_numbers_are_jumpers no)
		(fp_line
			(start 1.143 -0.5588)
			(end 1.143 0.5588)
			(stroke
				(width 0.1)
				(type default)
			)
			(layer "B.SilkS")
		)
		(fp_line
			(start -1.143 -0.5588)
			(end 1.143 -0.5588)
			(stroke
				(width 0.1)
				(type default)
			)
			(layer "B.SilkS")
		)
		(fp_line
			(start 1.143 0.5588)
			(end -1.143 0.5588)
			(stroke
				(width 0.1)
				(type default)
			)
			(layer "B.SilkS")
		)
		(fp_line
			(start -1.143 0.5588)
			(end -1.143 -0.5588)
			(stroke
				(width 0.1)
				(type default)
			)
			(layer "B.SilkS")
		)
		(fp_rect
			(start -1.143 -0.5588)
			(end 1.143 0.5588)
			(stroke
				(width 0)
				(type default)
			)
			(fill no)
			(layer "B.CrtYd")
		)
		(fp_line
			(start 0.508 -0.3048)
			(end 0.508 0.3048)
			(stroke
				(width 0.1)
				(type default)
			)
			(layer "B.Fab")
		)
		(fp_line
			(start -0.508 -0.3048)
			(end 0.508 -0.3048)
			(stroke
				(width 0.1)
				(type default)
			)
			(layer "B.Fab")
		)
		(fp_line
			(start 0.508 0.3048)
			(end -0.508 0.3048)
			(stroke
				(width 0.1)
				(type default)
			)
			(layer "B.Fab")
		)
		(fp_line
			(start -0.508 0.3048)
			(end -0.508 -0.3048)
			(stroke
				(width 0.1)
				(type default)
			)
			(layer "B.Fab")
		)
		(pad "1" smd rect
			(at 0.5334 0 270)
			(size 0.7112 0.6096)
			(layers "B.Cu" "B.Mask" "B.Paste")
			(net "XP3R3V_PG")
		)
		(pad "2" smd rect
			(at -0.5334 0 270)
			(size 0.7112 0.6096)
			(layers "B.Cu" "B.Mask" "B.Paste")
			(net "UNNAMED_523_CAPACITOR_I7_1")
		)
		(zone
			(layer "B.Cu")
			(hatch none 0.5)
			(connect_pads
				(clearance 0)
			)
			(min_thickness 0.25)
			(keepout
				(tracks allowed)
				(vias not_allowed)
				(pads allowed)
				(copperpour not_allowed)
				(footprints allowed)
			)
			(placement
				(enabled no)
				(sheetname "")
			)
			(fill
				(thermal_gap 0.5)
				(thermal_bridge_width 0.5)
				(island_removal_mode 0)
			)
			(polygon
				(pts
					(xy 139.6492 -59.4868) (xy 140.2588 -59.4868) (xy 140.2588 -59.6392) (xy 139.6492 -59.6392)
				)
			)
		)
	)
	(footprint ""
		(layer "B.Cu")
		(at 141.097 -15.9766 -90)
		(property "Reference" "R229"
			(at -5.7404 0.16637 270)
			(unlocked yes)
			(layer "B.SilkS")
			(effects
				(font
					(size 0.7874 0.5842)
					(thickness 0.1524)
				)
				(justify mirror)
			)
		)
		(property "Value" "VAL*"
			(at -0.02032 2.13233 270)
			(unlocked yes)
			(layer "B.Fab")
			(hide yes)
			(effects
				(font
					(size 0.7874 0.5842)
					(thickness 0.1524)
				)
				(justify mirror)
			)
		)
		(property "Tolerance" "TOL*"
			(at -0.044704 3.05435 270)
			(unlocked yes)
			(layer "Cmts.User")
			(hide yes)
			(effects
				(font
					(size 0.7874 0.5842)
					(thickness 0.1524)
				)
				(justify mirror)
			)
		)
		(property "User Part Number" "PARTNUM*"
			(at -0.02032 4.024884 270)
			(unlocked yes)
			(layer "Cmts.User")
			(hide yes)
			(effects
				(font
					(size 0.7874 0.5842)
					(thickness 0.1524)
				)
				(justify mirror)
			)
		)
		(property "Device Type" "RESISTOR-G155-14701-01,4.7KOHMA"
			(at -0.008382 1.210564 270)
			(unlocked yes)
			(layer "B.Fab")
			(hide yes)
			(effects
				(font
					(size 0.7874 0.5842)
					(thickness 0.1524)
				)
				(justify mirror)
			)
		)
		(duplicate_pad_numbers_are_jumpers no)
		(fp_line
			(start -1.143 0.5588)
			(end -1.143 -0.5588)
			(stroke
				(width 0.1)
				(type default)
			)
			(layer "B.SilkS")
		)
		(fp_line
			(start 1.143 0.5588)
			(end -1.143 0.5588)
			(stroke
				(width 0.1)
				(type default)
			)
			(layer "B.SilkS")
		)
		(fp_line
			(start -1.143 -0.5588)
			(end 1.143 -0.5588)
			(stroke
				(width 0.1)
				(type default)
			)
			(layer "B.SilkS")
		)
		(fp_line
			(start 1.143 -0.5588)
			(end 1.143 0.5588)
			(stroke
				(width 0.1)
				(type default)
			)
			(layer "B.SilkS")
		)
		(fp_rect
			(start -1.143 -0.5588)
			(end 1.143 0.5588)
			(stroke
				(width 0)
				(type default)
			)
			(fill no)
			(layer "B.CrtYd")
		)
		(fp_line
			(start -0.508 0.3048)
			(end -0.508 -0.3048)
			(stroke
				(width 0.1)
				(type default)
			)
			(layer "B.Fab")
		)
		(fp_line
			(start 0.508 0.3048)
			(end -0.508 0.3048)
			(stroke
				(width 0.1)
				(type default)
			)
			(layer "B.Fab")
		)
		(fp_line
			(start -0.508 -0.3048)
			(end 0.508 -0.3048)
			(stroke
				(width 0.1)
				(type default)
			)
			(layer "B.Fab")
		)
		(fp_line
			(start 0.508 -0.3048)
			(end 0.508 0.3048)
			(stroke
				(width 0.1)
				(type default)
			)
			(layer "B.Fab")
		)
		(pad "1" smd rect
			(at 0.5334 0 90)
			(size 0.7112 0.6096)
			(layers "B.Cu" "B.Mask" "B.Paste")
			(net "XP3R3V_FPGA")
		)
		(pad "2" smd rect
			(at -0.5334 0 90)
			(size 0.7112 0.6096)
			(layers "B.Cu" "B.Mask" "B.Paste")
			(net "UNNAMED_515_CAPACITOR_I138_1")
		)
		(zone
			(layer "B.Cu")
			(hatch none 0.5)
			(connect_pads
				(clearance 0)
			)
			(min_thickness 0.25)
			(keepout
				(tracks allowed)
				(vias not_allowed)
				(pads allowed)
				(copperpour not_allowed)
				(footprints allowed)
			)
			(placement
				(enabled no)
				(sheetname "")
			)
			(fill
				(thermal_gap 0.5)
				(thermal_bridge_width 0.5)
				(island_removal_mode 0)
			)
			(polygon
				(pts
					(xy 141.4018 -16.0528) (xy 140.7922 -16.0528) (xy 140.7922 -15.9004) (xy 141.4018 -15.9004)
				)
			)
		)
	)
)
